(kicad_pcb
	(version 20260206)
	(generator "pcbnew")
	(generator_version "10.0")
	(general
		(thickness 1.6)
		(legacy_teardrops no)
	)
	(paper "A4")
	(title_block
		(title "9054_F0T_PDB_BD_GPU_F_V04_1213_1550_OCP.brd")
		(comment 1 "Grand Teton / footprints 292-296 of 608")
	)
	(layers
		(0 "F.Cu" signal "TOP")
		(4 "In1.Cu" signal "GND")
		(6 "In2.Cu" signal "IN1")
		(8 "In3.Cu" signal "GND1")
		(10 "In4.Cu" signal "VCC")
		(12 "In5.Cu" signal "VCC1")
		(14 "In6.Cu" signal "GND2")
		(16 "In7.Cu" signal "IN2")
		(18 "In8.Cu" signal "GND3")
		(2 "B.Cu" signal "BOTTOM")
		(9 "F.Adhes" user "F.Adhesive")
		(11 "B.Adhes" user "B.Adhesive")
		(13 "F.Paste" user "Package Geometry/Pastemask Top")
		(15 "B.Paste" user "Package Geometry/Pastemask Bottom")
		(5 "F.SilkS" user "Ref Des/Silkscreen Top")
		(7 "B.SilkS" user "Ref Des/Silkscreen Bottom")
		(1 "F.Mask" user "Board Geometry/Soldermask Top")
		(3 "B.Mask" user "Board Geometry/Soldermask Bottom")
		(17 "Dwgs.User" user "User.Drawings")
		(19 "Cmts.User" user "User.Comments")
		(21 "Eco1.User" user "User.Eco1")
		(23 "Eco2.User" user "User.Eco2")
		(25 "Edge.Cuts" user "Board Geometry/Outline")
		(27 "Margin" user)
		(31 "F.CrtYd" user "Package Geometry/Place Bound Top")
		(29 "B.CrtYd" user "Package Geometry/Place Bound Bottom")
		(35 "F.Fab" user "Ref Des/Assembly Top")
		(33 "B.Fab" user "Ref Des/Assembly Bottom")
	)
	(footprint ""
		(layer "F.Cu")
		(at 306.7304 -36.1442 180)
		(property "Reference" "PR6965"
			(at 0 0 180)
			(layer "F.SilkS")
			(hide yes)
			(effects
				(font
					(size 1.27 1.27)
				)
			)
		)
		(property "Value" ""
			(at 0 0 180)
			(layer "F.Fab")
			(effects
				(font
					(size 1.27 1.27)
				)
			)
		)
		(duplicate_pad_numbers_are_jumpers no)
		(fp_line
			(start 1.2954 0.5842)
			(end -1.2954 0.5842)
			(stroke
				(width 0.1524)
				(type default)
			)
			(layer "F.SilkS")
		)
		(fp_line
			(start 1.2954 -0.5842)
			(end 1.2954 0.5842)
			(stroke
				(width 0.1524)
				(type default)
			)
			(layer "F.SilkS")
		)
		(fp_line
			(start -1.2954 0.5842)
			(end -1.2954 -0.5842)
			(stroke
				(width 0.1524)
				(type default)
			)
			(layer "F.SilkS")
		)
		(fp_line
			(start -1.2954 -0.5842)
			(end 1.2954 -0.5842)
			(stroke
				(width 0.1524)
				(type default)
			)
			(layer "F.SilkS")
		)
		(fp_line
			(start 1.1938 0.4064)
			(end 0.8636 0.4064)
			(stroke
				(width 0.1)
				(type default)
			)
			(layer "F.Fab")
		)
		(fp_line
			(start 1.1938 -0.406654)
			(end 1.1938 0.4064)
			(stroke
				(width 0.1)
				(type default)
			)
			(layer "F.Fab")
		)
		(fp_line
			(start 0.8636 0.4572)
			(end -0.8636 0.4572)
			(stroke
				(width 0.1)
				(type default)
			)
			(layer "F.Fab")
		)
		(fp_line
			(start 0.8636 0.4064)
			(end 0.8636 0.4572)
			(stroke
				(width 0.1)
				(type default)
			)
			(layer "F.Fab")
		)
		(fp_line
			(start 0.8636 -0.406654)
			(end 1.1938 -0.406654)
			(stroke
				(width 0.1)
				(type default)
			)
			(layer "F.Fab")
		)
		(fp_line
			(start 0.8636 -0.4572)
			(end 0.8636 -0.406654)
			(stroke
				(width 0.1)
				(type default)
			)
			(layer "F.Fab")
		)
		(fp_line
			(start -0.8636 0.4572)
			(end -0.8636 0.4318)
			(stroke
				(width 0.1)
				(type default)
			)
			(layer "F.Fab")
		)
		(fp_line
			(start -0.8636 0.4318)
			(end -0.8636 0.4064)
			(stroke
				(width 0.1)
				(type default)
			)
			(layer "F.Fab")
		)
		(fp_line
			(start -0.8636 0.4064)
			(end -1.1938 0.4064)
			(stroke
				(width 0.1)
				(type default)
			)
			(layer "F.Fab")
		)
		(fp_line
			(start -0.8636 -0.406654)
			(end -0.8636 -0.4572)
			(stroke
				(width 0.1)
				(type default)
			)
			(layer "F.Fab")
		)
		(fp_line
			(start -0.8636 -0.4572)
			(end 0.8636 -0.4572)
			(stroke
				(width 0.1)
				(type default)
			)
			(layer "F.Fab")
		)
		(fp_line
			(start -1.1938 0.4064)
			(end -1.1938 -0.406654)
			(stroke
				(width 0.1)
				(type default)
			)
			(layer "F.Fab")
		)
		(fp_line
			(start -1.1938 -0.406654)
			(end -0.8636 -0.406654)
			(stroke
				(width 0.1)
				(type default)
			)
			(layer "F.Fab")
		)
		(pad "1" smd rect
			(at -0.7366 0 90)
			(size 0.7112 0.8128)
			(layers "F.Cu" "F.Mask" "F.Paste")
			(net "P52V_HS1_SENSE_N_R2")
		)
		(pad "2" smd rect
			(at 0.7366 0 90)
			(size 0.7112 0.8128)
			(layers "F.Cu" "F.Mask" "F.Paste")
			(net "P52V_HS_4287_ADC_N")
		)
	)
	(footprint ""
		(layer "F.Cu")
		(at 438.023 -46.609 180)
		(property "Reference" "R387"
			(at 0 0 180)
			(layer "F.SilkS")
			(hide yes)
			(effects
				(font
					(size 1.27 1.27)
				)
			)
		)
		(property "Value" ""
			(at 0 0 180)
			(layer "F.Fab")
			(effects
				(font
					(size 1.27 1.27)
				)
			)
		)
		(duplicate_pad_numbers_are_jumpers no)
		(fp_line
			(start 0.7874 0.4064)
			(end -0.7874 0.4064)
			(stroke
				(width 0.1524)
				(type default)
			)
			(layer "F.SilkS")
		)
		(fp_line
			(start 0.7874 -0.4064)
			(end 0.7874 0.4064)
			(stroke
				(width 0.1524)
				(type default)
			)
			(layer "F.SilkS")
		)
		(fp_line
			(start -0.7874 0.4064)
			(end -0.7874 -0.4064)
			(stroke
				(width 0.1524)
				(type default)
			)
			(layer "F.SilkS")
		)
		(fp_line
			(start -0.7874 -0.4064)
			(end 0.7874 -0.4064)
			(stroke
				(width 0.1524)
				(type default)
			)
			(layer "F.SilkS")
		)
		(fp_line
			(start 0.67945 0.3048)
			(end 0.120396 0.3048)
			(stroke
				(width 0.1)
				(type default)
			)
			(layer "F.Fab")
		)
		(fp_line
			(start 0.67945 -0.3048)
			(end 0.67945 0.3048)
			(stroke
				(width 0.1)
				(type default)
			)
			(layer "F.Fab")
		)
		(fp_line
			(start 0.12065 -0.2794)
			(end 0.12065 -0.3048)
			(stroke
				(width 0.1)
				(type default)
			)
			(layer "F.Fab")
		)
		(fp_line
			(start 0.12065 -0.3048)
			(end 0.67945 -0.3048)
			(stroke
				(width 0.1)
				(type default)
			)
			(layer "F.Fab")
		)
		(fp_line
			(start 0.120396 0.3048)
			(end 0.120396 0.2794)
			(stroke
				(width 0.1)
				(type default)
			)
			(layer "F.Fab")
		)
		(fp_line
			(start 0.120396 0.2794)
			(end -0.12065 0.2794)
			(stroke
				(width 0.1)
				(type default)
			)
			(layer "F.Fab")
		)
		(fp_line
			(start -0.12065 0.3048)
			(end -0.67945 0.3048)
			(stroke
				(width 0.1)
				(type default)
			)
			(layer "F.Fab")
		)
		(fp_line
			(start -0.12065 0.2794)
			(end -0.12065 0.3048)
			(stroke
				(width 0.1)
				(type default)
			)
			(layer "F.Fab")
		)
		(fp_line
			(start -0.12065 -0.2794)
			(end 0.12065 -0.2794)
			(stroke
				(width 0.1)
				(type default)
			)
			(layer "F.Fab")
		)
		(fp_line
			(start -0.12065 -0.305054)
			(end -0.12065 -0.2794)
			(stroke
				(width 0.1)
				(type default)
			)
			(layer "F.Fab")
		)
		(fp_line
			(start -0.67945 0.3048)
			(end -0.67945 -0.305054)
			(stroke
				(width 0.1)
				(type default)
			)
			(layer "F.Fab")
		)
		(fp_line
			(start -0.67945 -0.305054)
			(end -0.12065 -0.305054)
			(stroke
				(width 0.1)
				(type default)
			)
			(layer "F.Fab")
		)
		(pad "1" smd circle
			(at -0.40005 0 180)
			(size 0 0)
			(layers "F.Cu" "F.Mask" "F.Paste")
			(net "GND")
		)
		(pad "2" smd circle
			(at 0.40005 0 180)
			(size 0 0)
			(layers "F.Cu" "F.Mask" "F.Paste")
			(net "PWRGD_P3V3_AUX_MB_BUF")
		)
	)
	(footprint ""
		(layer "F.Cu")
		(at 424.999912 -60.099956)
		(property "Reference" "H24"
			(at -1.048512 -8.961374 0)
			(unlocked yes)
			(layer "F.SilkS")
			(effects
				(font
					(size 0.7874 0.5842)
					(thickness 0.1524)
				)
				(justify left)
			)
		)
		(property "Value" ""
			(at 0 0 0)
			(layer "F.Fab")
			(effects
				(font
					(size 1.27 1.27)
				)
			)
		)
		(duplicate_pad_numbers_are_jumpers no)
		(fp_arc
			(start -7.611618 2.462276)
			(mid -1.24637 -7.902332)
			(end 7.999984 0)
			(stroke
				(width 0.1524)
				(type default)
			)
			(layer "F.SilkS")
		)
		(fp_arc
			(start 7.999984 0)
			(mid 2.498026 7.599939)
			(end -6.439916 4.746244)
			(stroke
				(width 0.1524)
				(type default)
			)
			(layer "F.SilkS")
		)
		(fp_circle
			(center 0 0)
			(end 7.999984 0)
			(stroke
				(width 0.1524)
				(type default)
			)
			(fill no)
			(layer "B.SilkS")
		)
		(fp_circle
			(center 0 0)
			(end 7.999984 0)
			(stroke
				(width 0.1)
				(type default)
			)
			(fill no)
			(layer "B.Fab")
		)
		(fp_circle
			(center 0 0)
			(end 7.999984 0)
			(stroke
				(width 0.1)
				(type default)
			)
			(fill no)
			(layer "F.Fab")
		)
		(pad "" np_thru_hole circle
			(at 0 0)
			(size 4.0132 4.0132)
			(drill 4.0132)
			(layers "*.Cu" "*.Mask")
			(clearance 0.381)
			(thermal_gap 0.381)
		)
		(pad "2" thru_hole circle
			(at 0 -3.50012)
			(size 0.762 0.762)
			(drill 0.5588)
			(layers "*.Cu" "*.Mask")
			(remove_unused_layers no)
			(net "GND")
			(clearance 0.1524)
			(thermal_gap 0.1524)
		)
		(pad "3" thru_hole circle
			(at -2.500122 -2.500122)
			(size 0.762 0.762)
			(drill 0.5588)
			(layers "*.Cu" "*.Mask")
			(remove_unused_layers no)
			(net "GND")
			(clearance 0.1524)
			(thermal_gap 0.1524)
		)
		(pad "4" thru_hole circle
			(at -3.50012 0)
			(size 0.762 0.762)
			(drill 0.5588)
			(layers "*.Cu" "*.Mask")
			(remove_unused_layers no)
			(net "GND")
			(clearance 0.1524)
			(thermal_gap 0.1524)
		)
		(pad "5" thru_hole circle
			(at -2.500122 2.500122)
			(size 0.762 0.762)
			(drill 0.5588)
			(layers "*.Cu" "*.Mask")
			(remove_unused_layers no)
			(net "GND")
			(clearance 0.1524)
			(thermal_gap 0.1524)
		)
		(pad "6" thru_hole circle
			(at 0 3.50012)
			(size 0.762 0.762)
			(drill 0.5588)
			(layers "*.Cu" "*.Mask")
			(remove_unused_layers no)
			(net "GND")
			(clearance 0.1524)
			(thermal_gap 0.1524)
		)
		(pad "7" thru_hole circle
			(at 2.500122 2.500122)
			(size 0.762 0.762)
			(drill 0.5588)
			(layers "*.Cu" "*.Mask")
			(remove_unused_layers no)
			(net "GND")
			(clearance 0.1524)
			(thermal_gap 0.1524)
		)
		(pad "8" thru_hole circle
			(at 3.50012 0)
			(size 0.762 0.762)
			(drill 0.5588)
			(layers "*.Cu" "*.Mask")
			(remove_unused_layers no)
			(net "GND")
			(clearance 0.1524)
			(thermal_gap 0.1524)
		)
		(pad "9" thru_hole circle
			(at 2.500122 -2.500122)
			(size 0.762 0.762)
			(drill 0.5588)
			(layers "*.Cu" "*.Mask")
			(remove_unused_layers no)
			(net "GND")
			(clearance 0.1524)
			(thermal_gap 0.1524)
		)
		(zone
			(layers "F.Cu" "B.Cu" "In1.Cu" "In2.Cu" "In3.Cu" "In4.Cu" "In5.Cu" "In6.Cu"
				"In7.Cu" "In8.Cu"
			)
			(hatch none 0.5)
			(connect_pads
				(clearance 0)
			)
			(min_thickness 0.25)
			(keepout
				(tracks not_allowed)
				(vias allowed)
				(pads allowed)
				(copperpour not_allowed)
				(footprints allowed)
			)
			(placement
				(enabled no)
				(sheetname "")
			)
			(fill
				(thermal_gap 0.5)
				(thermal_bridge_width 0.5)
				(island_removal_mode 0)
			)
			(polygon
				(pts
					(arc
						(start 427.514512 -60.099956)
						(mid 422.485312 -60.099956)
						(end 427.514512 -60.099956)
					)
				)
			)
		)
	)
	(footprint ""
		(layer "F.Cu")
		(at 419.87216 -26.00452)
		(property "Reference" "C96"
			(at 0 0 0)
			(layer "F.SilkS")
			(hide yes)
			(effects
				(font
					(size 1.27 1.27)
				)
			)
		)
		(property "Value" ""
			(at 0 0 0)
			(layer "F.Fab")
			(effects
				(font
					(size 1.27 1.27)
				)
			)
		)
		(duplicate_pad_numbers_are_jumpers no)
		(fp_line
			(start -0.7874 -0.4064)
			(end 0.7874 -0.4064)
			(stroke
				(width 0.1524)
				(type default)
			)
			(layer "F.SilkS")
		)
		(fp_line
			(start -0.7874 0.4064)
			(end -0.7874 -0.4064)
			(stroke
				(width 0.1524)
				(type default)
			)
			(layer "F.SilkS")
		)
		(fp_line
			(start 0.7874 -0.4064)
			(end 0.7874 0.4064)
			(stroke
				(width 0.1524)
				(type default)
			)
			(layer "F.SilkS")
		)
		(fp_line
			(start 0.7874 0.4064)
			(end -0.7874 0.4064)
			(stroke
				(width 0.1524)
				(type default)
			)
			(layer "F.SilkS")
		)
		(fp_line
			(start -0.6858 -0.3048)
			(end -0.1016 -0.3048)
			(stroke
				(width 0.1)
				(type default)
			)
			(layer "F.Fab")
		)
		(fp_line
			(start -0.6858 0.3048)
			(end -0.6858 -0.3048)
			(stroke
				(width 0.1)
				(type default)
			)
			(layer "F.Fab")
		)
		(fp_line
			(start -0.1016 -0.3048)
			(end -0.1016 -0.2794)
			(stroke
				(width 0.1)
				(type default)
			)
			(layer "F.Fab")
		)
		(fp_line
			(start -0.1016 -0.2794)
			(end 0.1016 -0.2794)
			(stroke
				(width 0.1)
				(type default)
			)
			(layer "F.Fab")
		)
		(fp_line
			(start -0.1016 0.2794)
			(end -0.1016 0.3048)
			(stroke
				(width 0.1)
				(type default)
			)
			(layer "F.Fab")
		)
		(fp_line
			(start -0.1016 0.3048)
			(end -0.6858 0.3048)
			(stroke
				(width 0.1)
				(type default)
			)
			(layer "F.Fab")
		)
		(fp_line
			(start 0.1016 -0.3048)
			(end 0.6858 -0.3048)
			(stroke
				(width 0.1)
				(type default)
			)
			(layer "F.Fab")
		)
		(fp_line
			(start 0.1016 -0.2794)
			(end 0.1016 -0.3048)
			(stroke
				(width 0.1)
				(type default)
			)
			(layer "F.Fab")
		)
		(fp_line
			(start 0.1016 0.2794)
			(end -0.1016 0.2794)
			(stroke
				(width 0.1)
				(type default)
			)
			(layer "F.Fab")
		)
		(fp_line
			(start 0.1016 0.3048)
			(end 0.1016 0.2794)
			(stroke
				(width 0.1)
				(type default)
			)
			(layer "F.Fab")
		)
		(fp_line
			(start 0.6858 -0.3048)
			(end 0.6858 0.3048)
			(stroke
				(width 0.1)
				(type default)
			)
			(layer "F.Fab")
		)
		(fp_line
			(start 0.6858 0.3048)
			(end 0.1016 0.3048)
			(stroke
				(width 0.1)
				(type default)
			)
			(layer "F.Fab")
		)
		(pad "1" smd rect
			(at -0.40005 0 180)
			(size 0.4572 0.508)
			(layers "F.Cu" "F.Mask" "F.Paste")
			(net "P12V_FAN_LED")
		)
		(pad "2" smd rect
			(at 0.40005 0 180)
			(size 0.4572 0.508)
			(layers "F.Cu" "F.Mask" "F.Paste")
			(net "GND")
		)
	)
	(footprint ""
		(layer "F.Cu")
		(at 145.11782 -36.1442)
		(property "Reference" "PR6991"
			(at 0 0 0)
			(layer "F.SilkS")
			(hide yes)
			(effects
				(font
					(size 1.27 1.27)
				)
			)
		)
		(property "Value" ""
			(at 0 0 0)
			(layer "F.Fab")
			(effects
				(font
					(size 1.27 1.27)
				)
			)
		)
		(duplicate_pad_numbers_are_jumpers no)
		(fp_line
			(start -1.2954 -0.5842)
			(end 1.2954 -0.5842)
			(stroke
				(width 0.1524)
				(type default)
			)
			(layer "F.SilkS")
		)
		(fp_line
			(start -1.2954 0.5842)
			(end -1.2954 -0.5842)
			(stroke
				(width 0.1524)
				(type default)
			)
			(layer "F.SilkS")
		)
		(fp_line
			(start 1.2954 -0.5842)
			(end 1.2954 0.5842)
			(stroke
				(width 0.1524)
				(type default)
			)
			(layer "F.SilkS")
		)
		(fp_line
			(start 1.2954 0.5842)
			(end -1.2954 0.5842)
			(stroke
				(width 0.1524)
				(type default)
			)
			(layer "F.SilkS")
		)
		(fp_line
			(start -1.1938 -0.406654)
			(end -0.8636 -0.406654)
			(stroke
				(width 0.1)
				(type default)
			)
			(layer "F.Fab")
		)
		(fp_line
			(start -1.1938 0.4064)
			(end -1.1938 -0.406654)
			(stroke
				(width 0.1)
				(type default)
			)
			(layer "F.Fab")
		)
		(fp_line
			(start -0.8636 -0.4572)
			(end 0.8636 -0.4572)
			(stroke
				(width 0.1)
				(type default)
			)
			(layer "F.Fab")
		)
		(fp_line
			(start -0.8636 -0.406654)
			(end -0.8636 -0.4572)
			(stroke
				(width 0.1)
				(type default)
			)
			(layer "F.Fab")
		)
		(fp_line
			(start -0.8636 0.4064)
			(end -1.1938 0.4064)
			(stroke
				(width 0.1)
				(type default)
			)
			(layer "F.Fab")
		)
		(fp_line
			(start -0.8636 0.4318)
			(end -0.8636 0.4064)
			(stroke
				(width 0.1)
				(type default)
			)
			(layer "F.Fab")
		)
		(fp_line
			(start -0.8636 0.4572)
			(end -0.8636 0.4318)
			(stroke
				(width 0.1)
				(type default)
			)
			(layer "F.Fab")
		)
		(fp_line
			(start 0.8636 -0.4572)
			(end 0.8636 -0.406654)
			(stroke
				(width 0.1)
				(type default)
			)
			(layer "F.Fab")
		)
		(fp_line
			(start 0.8636 -0.406654)
			(end 1.1938 -0.406654)
			(stroke
				(width 0.1)
				(type default)
			)
			(layer "F.Fab")
		)
		(fp_line
			(start 0.8636 0.4064)
			(end 0.8636 0.4572)
			(stroke
				(width 0.1)
				(type default)
			)
			(layer "F.Fab")
		)
		(fp_line
			(start 0.8636 0.4572)
			(end -0.8636 0.4572)
			(stroke
				(width 0.1)
				(type default)
			)
			(layer "F.Fab")
		)
		(fp_line
			(start 1.1938 -0.406654)
			(end 1.1938 0.4064)
			(stroke
				(width 0.1)
				(type default)
			)
			(layer "F.Fab")
		)
		(fp_line
			(start 1.1938 0.4064)
			(end 0.8636 0.4064)
			(stroke
				(width 0.1)
				(type default)
			)
			(layer "F.Fab")
		)
		(pad "1" smd rect
			(at -0.7366 0 270)
			(size 0.7112 0.8128)
			(layers "F.Cu" "F.Mask" "F.Paste")
			(net "P52V_HS2_1272_S_P")
		)
		(pad "2" smd rect
			(at 0.7366 0 270)
			(size 0.7112 0.8128)
			(layers "F.Cu" "F.Mask" "F.Paste")
			(net "P52V_HS2_SENSE_P_R2")
		)
	)
)
